(kicad_pcb
	(version 20260206)
	(generator "pcbnew")
	(generator_version "10.0")
	(general
		(thickness 1.6)
		(legacy_teardrops no)
	)
	(paper "A4")
	(title_block
		(title "dpb — 14545-sa.0730WZS0815.brd")
		(comment 1 "Honey Badger (Wiwynn) / footprints 613-620 of 1066")
	)
	(layers
		(0 "F.Cu" signal "TOP")
		(4 "In1.Cu" signal "L2GND")
		(6 "In2.Cu" signal "L3")
		(8 "In3.Cu" signal "L4VCC")
		(10 "In4.Cu" signal "L5VCC")
		(12 "In5.Cu" signal "L6")
		(14 "In6.Cu" signal "L7GND")
		(2 "B.Cu" signal "BOTTOM")
		(9 "F.Adhes" user "F.Adhesive")
		(11 "B.Adhes" user "B.Adhesive")
		(13 "F.Paste" user "Package Geometry/Pastemask Top")
		(15 "B.Paste" user "Package Geometry/Pastemask Bottom")
		(5 "F.SilkS" user "Ref Des/Silkscreen Top")
		(7 "B.SilkS" user "Ref Des/Silkscreen Bottom")
		(1 "F.Mask" user "Board Geometry/Soldermask Top")
		(3 "B.Mask" user "Board Geometry/Soldermask Bottom")
		(17 "Dwgs.User" user "User.Drawings")
		(19 "Cmts.User" user "User.Comments")
		(21 "Eco1.User" user "User.Eco1")
		(23 "Eco2.User" user "User.Eco2")
		(25 "Edge.Cuts" user "Board Geometry/Outline")
		(27 "Margin" user)
		(31 "F.CrtYd" user "Package Geometry/Place Bound Top")
		(29 "B.CrtYd" user "Package Geometry/Place Bound Bottom")
		(35 "F.Fab" user "Ref Des/Assembly Top")
		(33 "B.Fab" user "Ref Des/Assembly Bottom")
	)
	(footprint ""
		(layer "F.Cu")
		(at 187.464446 -460.790036 90)
		(property "Reference" "R345"
			(at 0 0 90)
			(layer "F.SilkS")
			(hide yes)
			(effects
				(font
					(size 1.27 1.27)
				)
			)
		)
		(property "Value" "4K7R2J-2-GP"
			(at 0.064008 -3.993896 90)
			(unlocked yes)
			(layer "F.Fab")
			(hide yes)
			(effects
				(font
					(size 1.016 1.016)
					(thickness 0.1524)
				)
			)
		)
		(property "Device Type" "R402H16"
			(at 0.064008 -5.517896 90)
			(unlocked yes)
			(layer "F.Fab")
			(hide yes)
			(effects
				(font
					(size 1.016 1.016)
					(thickness 0.1524)
				)
			)
		)
		(duplicate_pad_numbers_are_jumpers no)
		(fp_line
			(start 0.508 -0.9398)
			(end -0.508 -0.9398)
			(stroke
				(width 0.1524)
				(type default)
			)
			(layer "F.SilkS")
		)
		(fp_line
			(start -0.508 -0.9398)
			(end -0.508 0.9398)
			(stroke
				(width 0.1524)
				(type default)
			)
			(layer "F.SilkS")
		)
		(fp_rect
			(start -0.508 0.9398)
			(end 0.508 -0.9398)
			(stroke
				(width 0)
				(type default)
			)
			(fill no)
			(layer "F.CrtYd")
		)
		(fp_rect
			(start -0.508 0.9398)
			(end 0.508 -0.9398)
			(stroke
				(width 0)
				(type default)
			)
			(fill no)
			(layer "F.Fab")
		)
		(pad "1" smd custom
			(at 0 -0.4445 90)
			(size 0.1397 0.1397)
			(layers "F.Cu" "F.Mask" "F.Paste")
			(net "P3V3")
			(options
				(clearance outline)
				(anchor circle)
			)
			(primitives
				(gr_poly
					(pts
						(arc
							(start -0.1778 -0.2794)
							(mid -0.249642 -0.249642)
							(end -0.2794 -0.1778)
						)
						(arc
							(start -0.2794 0.1778)
							(mid -0.249642 0.249642)
							(end -0.1778 0.2794)
						)
						(arc
							(start 0.1778 0.2794)
							(mid 0.249642 0.249642)
							(end 0.2794 0.1778)
						)
						(arc
							(start 0.2794 -0.1778)
							(mid 0.249642 -0.249642)
							(end 0.1778 -0.2794)
						)
					)
					(width 0)
					(fill yes)
				)
			)
		)
		(pad "2" smd custom
			(at 0 0.4445 90)
			(size 0.1397 0.1397)
			(layers "F.Cu" "F.Mask" "F.Paste")
			(net "EEPROM_A0")
			(options
				(clearance outline)
				(anchor circle)
			)
			(primitives
				(gr_poly
					(pts
						(arc
							(start -0.1778 -0.2794)
							(mid -0.249642 -0.249642)
							(end -0.2794 -0.1778)
						)
						(arc
							(start -0.2794 0.1778)
							(mid -0.249642 0.249642)
							(end -0.1778 0.2794)
						)
						(arc
							(start 0.1778 0.2794)
							(mid 0.249642 0.249642)
							(end 0.2794 0.1778)
						)
						(arc
							(start 0.2794 -0.1778)
							(mid 0.249642 -0.249642)
							(end 0.1778 -0.2794)
						)
					)
					(width 0)
					(fill yes)
				)
			)
		)
	)
	(footprint ""
		(layer "F.Cu")
		(at 8.127746 -499.5037)
		(property "Reference" "PR44"
			(at 0 0 0)
			(layer "F.SilkS")
			(hide yes)
			(effects
				(font
					(size 1.27 1.27)
				)
			)
		)
		(property "Value" "0R2J-2-GP"
			(at 0.064008 -3.993896 0)
			(unlocked yes)
			(layer "F.Fab")
			(hide yes)
			(effects
				(font
					(size 1.016 1.016)
					(thickness 0.1524)
				)
			)
		)
		(property "Device Type" "R402H16"
			(at 0.064008 -5.517896 0)
			(unlocked yes)
			(layer "F.Fab")
			(hide yes)
			(effects
				(font
					(size 1.016 1.016)
					(thickness 0.1524)
				)
			)
		)
		(duplicate_pad_numbers_are_jumpers no)
		(fp_line
			(start -0.508 -0.9398)
			(end -0.508 0.9398)
			(stroke
				(width 0.1524)
				(type default)
			)
			(layer "F.SilkS")
		)
		(fp_line
			(start 0.508 -0.9398)
			(end -0.508 -0.9398)
			(stroke
				(width 0.1524)
				(type default)
			)
			(layer "F.SilkS")
		)
		(fp_rect
			(start -0.508 0.9398)
			(end 0.508 -0.9398)
			(stroke
				(width 0)
				(type default)
			)
			(fill no)
			(layer "F.CrtYd")
		)
		(fp_rect
			(start -0.508 0.9398)
			(end 0.508 -0.9398)
			(stroke
				(width 0)
				(type default)
			)
			(fill no)
			(layer "F.Fab")
		)
		(pad "1" smd custom
			(at 0 -0.4445)
			(size 0.1397 0.1397)
			(layers "F.Cu" "F.Mask" "F.Paste")
			(net "P5VC_MODE_PG")
			(options
				(clearance outline)
				(anchor circle)
			)
			(primitives
				(gr_poly
					(pts
						(arc
							(start -0.1778 -0.2794)
							(mid -0.249642 -0.249642)
							(end -0.2794 -0.1778)
						)
						(arc
							(start -0.2794 0.1778)
							(mid -0.249642 0.249642)
							(end -0.1778 0.2794)
						)
						(arc
							(start 0.1778 0.2794)
							(mid 0.249642 0.249642)
							(end 0.2794 0.1778)
						)
						(arc
							(start 0.2794 -0.1778)
							(mid 0.249642 -0.249642)
							(end 0.1778 -0.2794)
						)
					)
					(width 0)
					(fill yes)
				)
			)
		)
		(pad "2" smd custom
			(at 0 0.4445)
			(size 0.1397 0.1397)
			(layers "F.Cu" "F.Mask" "F.Paste")
			(net "P5VC_MODE")
			(options
				(clearance outline)
				(anchor circle)
			)
			(primitives
				(gr_poly
					(pts
						(arc
							(start -0.1778 -0.2794)
							(mid -0.249642 -0.249642)
							(end -0.2794 -0.1778)
						)
						(arc
							(start -0.2794 0.1778)
							(mid -0.249642 0.249642)
							(end -0.1778 0.2794)
						)
						(arc
							(start 0.1778 0.2794)
							(mid 0.249642 0.249642)
							(end 0.2794 0.1778)
						)
						(arc
							(start 0.2794 -0.1778)
							(mid 0.249642 -0.249642)
							(end 0.1778 -0.2794)
						)
					)
					(width 0)
					(fill yes)
				)
			)
		)
	)
	(footprint ""
		(layer "F.Cu")
		(at 217.799412 -64.242696 -90)
		(property "Reference" "C169"
			(at 0 0 270)
			(layer "F.SilkS")
			(hide yes)
			(effects
				(font
					(size 1.27 1.27)
				)
			)
		)
		(property "Value" "SCD01U50V2KX-1GP"
			(at 1.1811 -2.7051 270)
			(unlocked yes)
			(layer "F.Fab")
			(hide yes)
			(effects
				(font
					(size 1.016 1.016)
					(thickness 0.1524)
				)
			)
		)
		(property "Device Type" "C402H22"
			(at 1.1811 -4.2291 270)
			(unlocked yes)
			(layer "F.Fab")
			(hide yes)
			(effects
				(font
					(size 1.016 1.016)
					(thickness 0.1524)
				)
			)
		)
		(duplicate_pad_numbers_are_jumpers no)
		(fp_rect
			(start -0.4318 0.9525)
			(end 0.4318 -0.9525)
			(stroke
				(width 0)
				(type default)
			)
			(fill no)
			(layer "F.CrtYd")
		)
		(fp_rect
			(start -0.4318 0.9525)
			(end 0.4318 -0.9525)
			(stroke
				(width 0)
				(type default)
			)
			(fill no)
			(layer "F.Fab")
		)
		(pad "1" smd custom
			(at 0 -0.4445 270)
			(size 0.1524 0.1524)
			(layers "F.Cu" "F.Mask" "F.Paste")
			(net "SAS2X28_DRIVE_RX_P_B4")
			(options
				(clearance outline)
				(anchor circle)
			)
			(primitives
				(gr_poly
					(pts
						(arc
							(start 0.3048 -0.2032)
							(mid 0.275042 -0.275042)
							(end 0.2032 -0.3048)
						)
						(arc
							(start -0.2032 -0.3048)
							(mid -0.275042 -0.275042)
							(end -0.3048 -0.2032)
						)
						(arc
							(start -0.3048 0.2032)
							(mid -0.275042 0.275042)
							(end -0.2032 0.3048)
						)
						(arc
							(start 0.2032 0.3048)
							(mid 0.275042 0.275042)
							(end 0.3048 0.2032)
						)
					)
					(width 0)
					(fill yes)
				)
			)
		)
		(pad "2" smd custom
			(at 0 0.4445 270)
			(size 0.1524 0.1524)
			(layers "F.Cu" "F.Mask" "F.Paste")
			(net "SAS2X28_B_HDD4_RX_+")
			(options
				(clearance outline)
				(anchor circle)
			)
			(primitives
				(gr_poly
					(pts
						(arc
							(start 0.3048 -0.2032)
							(mid 0.275042 -0.275042)
							(end 0.2032 -0.3048)
						)
						(arc
							(start -0.2032 -0.3048)
							(mid -0.275042 -0.275042)
							(end -0.3048 -0.2032)
						)
						(arc
							(start -0.3048 0.2032)
							(mid -0.275042 0.275042)
							(end -0.2032 0.3048)
						)
						(arc
							(start 0.2032 0.3048)
							(mid 0.275042 0.275042)
							(end 0.3048 0.2032)
						)
					)
					(width 0)
					(fill yes)
				)
			)
		)
	)
	(footprint ""
		(layer "F.Cu")
		(at 41.960546 -133.3119 -90)
		(property "Reference" "R324"
			(at 0 0 270)
			(layer "F.SilkS")
			(hide yes)
			(effects
				(font
					(size 1.27 1.27)
				)
			)
		)
		(property "Value" "4K7R2J-2-GP"
			(at 0.064008 -3.993896 270)
			(unlocked yes)
			(layer "F.Fab")
			(hide yes)
			(effects
				(font
					(size 1.016 1.016)
					(thickness 0.1524)
				)
			)
		)
		(property "Device Type" "R402H16"
			(at 0.064008 -5.517896 270)
			(unlocked yes)
			(layer "F.Fab")
			(hide yes)
			(effects
				(font
					(size 1.016 1.016)
					(thickness 0.1524)
				)
			)
		)
		(duplicate_pad_numbers_are_jumpers no)
		(fp_line
			(start -0.508 -0.9398)
			(end -0.508 0.9398)
			(stroke
				(width 0.1524)
				(type default)
			)
			(layer "F.SilkS")
		)
		(fp_line
			(start 0.508 -0.9398)
			(end -0.508 -0.9398)
			(stroke
				(width 0.1524)
				(type default)
			)
			(layer "F.SilkS")
		)
		(fp_rect
			(start -0.508 0.9398)
			(end 0.508 -0.9398)
			(stroke
				(width 0)
				(type default)
			)
			(fill no)
			(layer "F.CrtYd")
		)
		(fp_rect
			(start -0.508 0.9398)
			(end 0.508 -0.9398)
			(stroke
				(width 0)
				(type default)
			)
			(fill no)
			(layer "F.Fab")
		)
		(pad "1" smd custom
			(at 0 -0.4445 270)
			(size 0.1397 0.1397)
			(layers "F.Cu" "F.Mask" "F.Paste")
			(net "I2C_B_TMP2_A1")
			(options
				(clearance outline)
				(anchor circle)
			)
			(primitives
				(gr_poly
					(pts
						(arc
							(start -0.1778 -0.2794)
							(mid -0.249642 -0.249642)
							(end -0.2794 -0.1778)
						)
						(arc
							(start -0.2794 0.1778)
							(mid -0.249642 0.249642)
							(end -0.1778 0.2794)
						)
						(arc
							(start 0.1778 0.2794)
							(mid 0.249642 0.249642)
							(end 0.2794 0.1778)
						)
						(arc
							(start 0.2794 -0.1778)
							(mid 0.249642 -0.249642)
							(end 0.1778 -0.2794)
						)
					)
					(width 0)
					(fill yes)
				)
			)
		)
		(pad "2" smd custom
			(at 0 0.4445 270)
			(size 0.1397 0.1397)
			(layers "F.Cu" "F.Mask" "F.Paste")
			(net "GND")
			(options
				(clearance outline)
				(anchor circle)
			)
			(primitives
				(gr_poly
					(pts
						(arc
							(start -0.1778 -0.2794)
							(mid -0.249642 -0.249642)
							(end -0.2794 -0.1778)
						)
						(arc
							(start -0.2794 0.1778)
							(mid -0.249642 0.249642)
							(end -0.1778 0.2794)
						)
						(arc
							(start 0.1778 0.2794)
							(mid 0.249642 0.249642)
							(end 0.2794 0.1778)
						)
						(arc
							(start 0.2794 -0.1778)
							(mid 0.249642 -0.249642)
							(end 0.1778 -0.2794)
						)
					)
					(width 0)
					(fill yes)
				)
			)
		)
	)
	(footprint ""
		(layer "F.Cu")
		(at 32.12592 -277.998428 -90)
		(property "Reference" "R451"
			(at 0 0 270)
			(layer "F.SilkS")
			(hide yes)
			(effects
				(font
					(size 1.27 1.27)
				)
			)
		)
		(property "Value" "4K7R2J-2-GP"
			(at 0.064008 -3.993896 270)
			(unlocked yes)
			(layer "F.Fab")
			(hide yes)
			(effects
				(font
					(size 1.016 1.016)
					(thickness 0.1524)
				)
			)
		)
		(property "Device Type" "R402H16"
			(at 0.064008 -5.517896 270)
			(unlocked yes)
			(layer "F.Fab")
			(hide yes)
			(effects
				(font
					(size 1.016 1.016)
					(thickness 0.1524)
				)
			)
		)
		(duplicate_pad_numbers_are_jumpers no)
		(fp_line
			(start -0.508 -0.9398)
			(end -0.508 0.9398)
			(stroke
				(width 0.1524)
				(type default)
			)
			(layer "F.SilkS")
		)
		(fp_line
			(start 0.508 -0.9398)
			(end -0.508 -0.9398)
			(stroke
				(width 0.1524)
				(type default)
			)
			(layer "F.SilkS")
		)
		(fp_rect
			(start -0.508 0.9398)
			(end 0.508 -0.9398)
			(stroke
				(width 0)
				(type default)
			)
			(fill no)
			(layer "F.CrtYd")
		)
		(fp_rect
			(start -0.508 0.9398)
			(end 0.508 -0.9398)
			(stroke
				(width 0)
				(type default)
			)
			(fill no)
			(layer "F.Fab")
		)
		(pad "1" smd custom
			(at 0 -0.4445 270)
			(size 0.1397 0.1397)
			(layers "F.Cu" "F.Mask" "F.Paste")
			(net "P3V3")
			(options
				(clearance outline)
				(anchor circle)
			)
			(primitives
				(gr_poly
					(pts
						(arc
							(start -0.1778 -0.2794)
							(mid -0.249642 -0.249642)
							(end -0.2794 -0.1778)
						)
						(arc
							(start -0.2794 0.1778)
							(mid -0.249642 0.249642)
							(end -0.1778 0.2794)
						)
						(arc
							(start 0.1778 0.2794)
							(mid 0.249642 0.249642)
							(end 0.2794 0.1778)
						)
						(arc
							(start 0.2794 -0.1778)
							(mid 0.249642 -0.249642)
							(end 0.1778 -0.2794)
						)
					)
					(width 0)
					(fill yes)
				)
			)
		)
		(pad "2" smd custom
			(at 0 0.4445 270)
			(size 0.1397 0.1397)
			(layers "F.Cu" "F.Mask" "F.Paste")
			(net "SAS_EXP_B_PWR7")
			(options
				(clearance outline)
				(anchor circle)
			)
			(primitives
				(gr_poly
					(pts
						(arc
							(start -0.1778 -0.2794)
							(mid -0.249642 -0.249642)
							(end -0.2794 -0.1778)
						)
						(arc
							(start -0.2794 0.1778)
							(mid -0.249642 0.249642)
							(end -0.1778 0.2794)
						)
						(arc
							(start 0.1778 0.2794)
							(mid 0.249642 0.249642)
							(end 0.2794 0.1778)
						)
						(arc
							(start 0.2794 -0.1778)
							(mid 0.249642 -0.249642)
							(end 0.1778 -0.2794)
						)
					)
					(width 0)
					(fill yes)
				)
			)
		)
	)
	(footprint ""
		(layer "F.Cu")
		(at 77.977746 -84.8487 -90)
		(property "Reference" "R231"
			(at 0 0 270)
			(layer "F.SilkS")
			(hide yes)
			(effects
				(font
					(size 1.27 1.27)
				)
			)
		)
		(property "Value" "1KR2F-3-GP"
			(at 0.064008 -3.993896 270)
			(unlocked yes)
			(layer "F.Fab")
			(hide yes)
			(effects
				(font
					(size 1.016 1.016)
					(thickness 0.1524)
				)
			)
		)
		(property "Device Type" "R402H16"
			(at 0.064008 -5.517896 270)
			(unlocked yes)
			(layer "F.Fab")
			(hide yes)
			(effects
				(font
					(size 1.016 1.016)
					(thickness 0.1524)
				)
			)
		)
		(duplicate_pad_numbers_are_jumpers no)
		(fp_line
			(start -0.508 -0.9398)
			(end -0.508 0.9398)
			(stroke
				(width 0.1524)
				(type default)
			)
			(layer "F.SilkS")
		)
		(fp_line
			(start 0.508 -0.9398)
			(end -0.508 -0.9398)
			(stroke
				(width 0.1524)
				(type default)
			)
			(layer "F.SilkS")
		)
		(fp_rect
			(start -0.508 0.9398)
			(end 0.508 -0.9398)
			(stroke
				(width 0)
				(type default)
			)
			(fill no)
			(layer "F.CrtYd")
		)
		(fp_rect
			(start -0.508 0.9398)
			(end 0.508 -0.9398)
			(stroke
				(width 0)
				(type default)
			)
			(fill no)
			(layer "F.Fab")
		)
		(pad "1" smd custom
			(at 0 -0.4445 270)
			(size 0.1397 0.1397)
			(layers "F.Cu" "F.Mask" "F.Paste")
			(net "P3V3")
			(options
				(clearance outline)
				(anchor circle)
			)
			(primitives
				(gr_poly
					(pts
						(arc
							(start -0.1778 -0.2794)
							(mid -0.249642 -0.249642)
							(end -0.2794 -0.1778)
						)
						(arc
							(start -0.2794 0.1778)
							(mid -0.249642 0.249642)
							(end -0.1778 0.2794)
						)
						(arc
							(start 0.1778 0.2794)
							(mid 0.249642 0.249642)
							(end 0.2794 0.1778)
						)
						(arc
							(start 0.2794 -0.1778)
							(mid 0.249642 -0.249642)
							(end 0.1778 -0.2794)
						)
					)
					(width 0)
					(fill yes)
				)
			)
		)
		(pad "2" smd custom
			(at 0 0.4445 270)
			(size 0.1397 0.1397)
			(layers "F.Cu" "F.Mask" "F.Paste")
			(net "SW_PWR_HDD9")
			(options
				(clearance outline)
				(anchor circle)
			)
			(primitives
				(gr_poly
					(pts
						(arc
							(start -0.1778 -0.2794)
							(mid -0.249642 -0.249642)
							(end -0.2794 -0.1778)
						)
						(arc
							(start -0.2794 0.1778)
							(mid -0.249642 0.249642)
							(end -0.1778 0.2794)
						)
						(arc
							(start 0.1778 0.2794)
							(mid 0.249642 0.249642)
							(end 0.2794 0.1778)
						)
						(arc
							(start 0.2794 -0.1778)
							(mid 0.249642 -0.249642)
							(end 0.1778 -0.2794)
						)
					)
					(width 0)
					(fill yes)
				)
			)
		)
	)
	(footprint ""
		(layer "F.Cu")
		(at 53.848 -129.921)
		(property "Reference" "C377"
			(at 0 0 0)
			(layer "F.SilkS")
			(hide yes)
			(effects
				(font
					(size 1.27 1.27)
				)
			)
		)
		(property "Value" "SCD033U25V2KX-GP"
			(at 1.1811 -2.7051 0)
			(unlocked yes)
			(layer "F.Fab")
			(hide yes)
			(effects
				(font
					(size 1.016 1.016)
					(thickness 0.1524)
				)
			)
		)
		(property "Device Type" "C402H22"
			(at 1.1811 -4.2291 0)
			(unlocked yes)
			(layer "F.Fab")
			(hide yes)
			(effects
				(font
					(size 1.016 1.016)
					(thickness 0.1524)
				)
			)
		)
		(duplicate_pad_numbers_are_jumpers no)
		(fp_rect
			(start -0.4318 0.9525)
			(end 0.4318 -0.9525)
			(stroke
				(width 0)
				(type default)
			)
			(fill no)
			(layer "F.CrtYd")
		)
		(fp_rect
			(start -0.4318 0.9525)
			(end 0.4318 -0.9525)
			(stroke
				(width 0)
				(type default)
			)
			(fill no)
			(layer "F.Fab")
		)
		(pad "1" smd custom
			(at 0 -0.4445)
			(size 0.1524 0.1524)
			(layers "F.Cu" "F.Mask" "F.Paste")
			(net "SW_HDD13_P")
			(options
				(clearance outline)
				(anchor circle)
			)
			(primitives
				(gr_poly
					(pts
						(arc
							(start 0.3048 -0.2032)
							(mid 0.275042 -0.275042)
							(end 0.2032 -0.3048)
						)
						(arc
							(start -0.2032 -0.3048)
							(mid -0.275042 -0.275042)
							(end -0.3048 -0.2032)
						)
						(arc
							(start -0.3048 0.2032)
							(mid -0.275042 0.275042)
							(end -0.2032 0.3048)
						)
						(arc
							(start 0.2032 0.3048)
							(mid 0.275042 0.275042)
							(end 0.3048 0.2032)
						)
					)
					(width 0)
					(fill yes)
				)
			)
		)
		(pad "2" smd custom
			(at 0 0.4445)
			(size 0.1524 0.1524)
			(layers "F.Cu" "F.Mask" "F.Paste")
			(net "GND")
			(options
				(clearance outline)
				(anchor circle)
			)
			(primitives
				(gr_poly
					(pts
						(arc
							(start 0.3048 -0.2032)
							(mid 0.275042 -0.275042)
							(end 0.2032 -0.3048)
						)
						(arc
							(start -0.2032 -0.3048)
							(mid -0.275042 -0.275042)
							(end -0.3048 -0.2032)
						)
						(arc
							(start -0.3048 0.2032)
							(mid -0.275042 0.275042)
							(end -0.2032 0.3048)
						)
						(arc
							(start 0.2032 0.3048)
							(mid 0.275042 0.275042)
							(end 0.3048 0.2032)
						)
					)
					(width 0)
					(fill yes)
				)
			)
		)
	)
	(footprint ""
		(layer "F.Cu")
		(at 233.933746 -26.1747)
		(property "Reference" "TP19"
			(at 0 0 0)
			(layer "F.SilkS")
			(hide yes)
			(effects
				(font
					(size 1.27 1.27)
				)
			)
		)
		(property "Value" "TPAD32-GP"
			(at 0 -3.166364 0)
			(unlocked yes)
			(layer "F.Fab")
			(hide yes)
			(effects
				(font
					(size 1.016 1.016)
					(thickness 0.1524)
				)
			)
		)
		(property "Device Type" "TPAD32"
			(at 0 -4.690618 0)
			(unlocked yes)
			(layer "F.Fab")
			(hide yes)
			(effects
				(font
					(size 1.016 1.016)
					(thickness 0.1524)
				)
			)
		)
		(duplicate_pad_numbers_are_jumpers no)
		(fp_poly
			(pts
				(arc
					(start 0.4064 0)
					(mid -0.4064 0)
					(end 0.4064 0)
				)
			)
			(stroke
				(width 0)
				(type default)
			)
			(fill no)
			(layer "F.CrtYd")
		)
		(fp_poly
			(pts
				(arc
					(start 0.7112 0)
					(mid -0.7112 0)
					(end 0.7112 0)
				)
			)
			(stroke
				(width 0)
				(type default)
			)
			(fill no)
			(layer "F.Fab")
		)
		(pad "1" smd circle
			(at 0 0)
			(size 0.8128 0.8128)
			(layers "F.Cu" "F.Mask" "F.Paste")
			(net "P5VA_EN")
		)
	)
)
